(kicad_pcb
	(version 20240108)
	(generator "pcbnew")
	(generator_version "8.0")
	(general
		(thickness 1.62)
		(legacy_teardrops no)
	)
	(paper "A4")
	(title_block
		(title "Jetson Orin Baseboard")
		(date "2025-03-12")
		(rev "1.3.4")
		(company "Antmicro Ltd")
		(comment 1 "www.antmicro.com")
		(comment 9 "footprints 381-384 of 677")
	)
	(layers
		(0 "F.Cu" signal)
		(1 "In1.Cu" signal)
		(2 "In2.Cu" signal)
		(3 "In3.Cu" signal)
		(4 "In4.Cu" jumper)
		(5 "In5.Cu" signal)
		(6 "In6.Cu" signal)
		(31 "B.Cu" signal)
		(32 "B.Adhes" user "B.Adhesive")
		(33 "F.Adhes" user "F.Adhesive")
		(34 "B.Paste" user)
		(35 "F.Paste" user)
		(36 "B.SilkS" user "B.Silkscreen")
		(37 "F.SilkS" user "F.Silkscreen")
		(38 "B.Mask" user)
		(39 "F.Mask" user)
		(40 "Dwgs.User" user "User.Drawings")
		(41 "Cmts.User" user "User.Comments")
		(42 "Eco1.User" user "User.Eco1")
		(43 "Eco2.User" user "User.Eco2")
		(44 "Edge.Cuts" user)
		(45 "Margin" user)
		(46 "B.CrtYd" user "B.Courtyard")
		(47 "F.CrtYd" user "F.Courtyard")
		(48 "B.Fab" user)
		(49 "F.Fab" user)
	)
	(footprint "antmicro-footprints:SOD-923"
		(layer "B.Cu")
		(at 74.5 112.45)
		(property "Reference" "D7"
			(at 1.66 1.41 0)
			(unlocked yes)
			(layer "B.SilkS")
			(effects
				(font
					(size 0.7 0.7)
					(thickness 0.15)
				)
				(justify left bottom mirror)
			)
		)
		(property "Value" "DF2S30FS_SOD"
			(at 0 -1.3 180)
			(unlocked yes)
			(layer "B.Fab")
			(effects
				(font
					(size 0.7 0.7)
					(thickness 0.15)
				)
				(justify left bottom mirror)
			)
		)
		(property "Footprint" "antmicro-footprints:SOD-923"
			(at 0 0 0)
			(layer "F.Fab")
			(hide yes)
			(effects
				(font
					(size 1.27 1.27)
					(thickness 0.15)
				)
			)
		)
		(property "Datasheet" "https://toshiba.semicon-storage.com/info/DF2S30FS_datasheet_en_20211216.pdf?did=11156&prodName=DF2S30FS"
			(at 0 0 0)
			(layer "F.Fab")
			(hide yes)
			(effects
				(font
					(size 1.27 1.27)
					(thickness 0.15)
				)
			)
		)
		(property "Author" "Antmicro"
			(at 0 0 0)
			(layer "B.Fab")
			(hide yes)
			(effects
				(font
					(size 1 1)
					(thickness 0.15)
				)
				(justify mirror)
			)
		)
		(property "License" "Apache-2.0"
			(at 0 0 0)
			(layer "B.Fab")
			(hide yes)
			(effects
				(font
					(size 1 1)
					(thickness 0.15)
				)
				(justify mirror)
			)
		)
		(property "MPN" "DF2S30FS"
			(at 0 0 0)
			(layer "B.Fab")
			(hide yes)
			(effects
				(font
					(size 1 1)
					(thickness 0.15)
				)
				(justify mirror)
			)
		)
		(property "Manufacturer" "Toshiba"
			(at 0 0 0)
			(layer "B.Fab")
			(hide yes)
			(effects
				(font
					(size 1 1)
					(thickness 0.15)
				)
				(justify mirror)
			)
		)
		(sheetname "USB Debug, DP")
		(sheetfile "usb.kicad_sch")
		(attr smd)
		(fp_line
			(start -0.5 -0.3)
			(end -0.5 -0.4)
			(stroke
				(width 0.15)
				(type solid)
			)
			(layer "B.SilkS")
		)
		(fp_line
			(start -0.5 0.4)
			(end -0.5 0.3)
			(stroke
				(width 0.15)
				(type solid)
			)
			(layer "B.SilkS")
		)
		(fp_line
			(start -0.16 -0.4)
			(end -0.16 0.4)
			(stroke
				(width 0.15)
				(type solid)
			)
			(layer "B.SilkS")
		)
		(fp_line
			(start 0.5 -0.4)
			(end -0.5 -0.4)
			(stroke
				(width 0.15)
				(type solid)
			)
			(layer "B.SilkS")
		)
		(fp_line
			(start 0.5 -0.3)
			(end 0.5 -0.4)
			(stroke
				(width 0.15)
				(type solid)
			)
			(layer "B.SilkS")
		)
		(fp_line
			(start 0.5 0.3)
			(end 0.5 0.4)
			(stroke
				(width 0.15)
				(type solid)
			)
			(layer "B.SilkS")
		)
		(fp_line
			(start 0.5 0.4)
			(end -0.5 0.4)
			(stroke
				(width 0.15)
				(type solid)
			)
			(layer "B.SilkS")
		)
		(fp_rect
			(start -0.68 0.41)
			(end 0.68 -0.41)
			(stroke
				(width 0.05)
				(type solid)
			)
			(fill none)
			(layer "B.CrtYd")
		)
		(fp_line
			(start -0.202 -0.298)
			(end -0.202 0.3)
			(stroke
				(width 0.15)
				(type solid)
			)
			(layer "B.Fab")
		)
		(fp_rect
			(start -0.402 0.3)
			(end 0.4 -0.298)
			(stroke
				(width 0.15)
				(type solid)
			)
			(fill none)
			(layer "B.Fab")
		)
		(fp_text user "License: Apache-2.0"
			(at -0.68 -4.5 180)
			(layer "B.Fab")
			(hide yes)
			(effects
				(font
					(size 0.7 0.7)
					(thickness 0.15)
				)
				(justify left bottom mirror)
			)
		)
		(fp_text user "${REFERENCE}"
			(at -0.68 -3.3 180)
			(unlocked yes)
			(layer "B.Fab")
			(hide yes)
			(effects
				(font
					(size 0.7 0.7)
					(thickness 0.15)
				)
				(justify left bottom mirror)
			)
		)
		(fp_text user "Author: Antmicro"
			(at -0.68 -5.7 180)
			(layer "B.Fab")
			(hide yes)
			(effects
				(font
					(size 0.7 0.7)
					(thickness 0.15)
				)
				(justify left bottom mirror)
			)
		)
		(pad "1" smd roundrect
			(at -0.438 0)
			(size 0.4 0.325)
			(layers "B.Cu" "B.Paste" "B.Mask")
			(roundrect_rratio 0.25)
			(net 261 "/USB Debug, DP/USBC0_VBUS")
			(pinfunction "C")
			(pintype "passive")
		)
		(pad "2" smd roundrect
			(at 0.436 0)
			(size 0.4 0.325)
			(layers "B.Cu" "B.Paste" "B.Mask")
			(roundrect_rratio 0.25)
			(net 1 "GND")
			(pinfunction "A")
			(pintype "passive")
		)
	)
	(footprint "antmicro-footprints:R_0402_1005Metric"
		(layer "B.Cu")
		(at 88 112.6 90)
		(descr "Resistor SMD 0402")
		(tags "resistor SMD 0402")
		(property "Reference" "R216"
			(at 0.965 -3.55 -90)
			(layer "B.SilkS")
			(effects
				(font
					(size 0.7 0.7)
					(thickness 0.15)
				)
				(justify left bottom mirror)
			)
		)
		(property "Value" "R_0R_0402"
			(at 0 -1.4 -90)
			(layer "B.Fab")
			(effects
				(font
					(size 0.7 0.7)
					(thickness 0.15)
				)
				(justify left bottom mirror)
			)
		)
		(property "Footprint" "antmicro-footprints:R_0402_1005Metric"
			(at 0 0 90)
			(layer "F.Fab")
			(hide yes)
			(effects
				(font
					(size 1.27 1.27)
					(thickness 0.15)
				)
			)
		)
		(property "Datasheet" "https://industrial.panasonic.com/cdbs/www-data/pdf/RDA0000/AOA0000C301.pdf"
			(at 0 0 90)
			(layer "F.Fab")
			(hide yes)
			(effects
				(font
					(size 1.27 1.27)
					(thickness 0.15)
				)
			)
		)
		(property "Author" "Antmicro"
			(at 200.6 24.6 0)
			(layer "B.Fab")
			(hide yes)
			(effects
				(font
					(size 1 1)
					(thickness 0.15)
				)
				(justify mirror)
			)
		)
		(property "Current" "1A"
			(at 200.6 24.6 0)
			(layer "B.Fab")
			(hide yes)
			(effects
				(font
					(size 1 1)
					(thickness 0.15)
				)
				(justify mirror)
			)
		)
		(property "License" "Apache-2.0"
			(at 200.6 24.6 0)
			(layer "B.Fab")
			(hide yes)
			(effects
				(font
					(size 1 1)
					(thickness 0.15)
				)
				(justify mirror)
			)
		)
		(property "MPN" "ERJ2GE0R00X"
			(at 200.6 24.6 0)
			(layer "B.Fab")
			(hide yes)
			(effects
				(font
					(size 1 1)
					(thickness 0.15)
				)
				(justify mirror)
			)
		)
		(property "Manufacturer" "Panasonic"
			(at 200.6 24.6 0)
			(layer "B.Fab")
			(hide yes)
			(effects
				(font
					(size 1 1)
					(thickness 0.15)
				)
				(justify mirror)
			)
		)
		(property "Tolerance" ""
			(at 200.6 24.6 0)
			(layer "B.Fab")
			(hide yes)
			(effects
				(font
					(size 1 1)
					(thickness 0.15)
				)
				(justify mirror)
			)
		)
		(property "Val" "0R"
			(at 200.6 24.6 0)
			(layer "B.Fab")
			(hide yes)
			(effects
				(font
					(size 1 1)
					(thickness 0.15)
				)
				(justify mirror)
			)
		)
		(sheetname "Peripherals")
		(sheetfile "peripherals.kicad_sch")
		(attr smd)
		(fp_rect
			(start -0.925 0.47)
			(end 0.925 -0.47)
			(stroke
				(width 0.05)
				(type default)
			)
			(fill none)
			(layer "B.CrtYd")
		)
		(fp_rect
			(start -0.5 0.25)
			(end 0.5 -0.25)
			(stroke
				(width 0.15)
				(type solid)
			)
			(fill none)
			(layer "B.Fab")
		)
		(fp_text user "Author: Antmicro"
			(at -0.95 -4.169 -90)
			(layer "B.Fab")
			(hide yes)
			(effects
				(font
					(size 0.7 0.7)
					(thickness 0.15)
				)
				(justify left bottom mirror)
			)
		)
		(fp_text user "License: Apache-2.0"
			(at -0.95 -5.169 -90)
			(layer "B.Fab")
			(hide yes)
			(effects
				(font
					(size 0.7 0.7)
					(thickness 0.15)
				)
				(justify left bottom mirror)
			)
		)
		(fp_text user "${REFERENCE}"
			(at -0.95 -3.168 -90)
			(layer "B.Fab")
			(hide yes)
			(effects
				(font
					(size 0.7 0.7)
					(thickness 0.15)
				)
				(justify left bottom mirror)
			)
		)
		(pad "1" smd roundrect
			(at -0.48 0 90)
			(size 0.59 0.64)
			(layers "B.Cu" "B.Paste" "B.Mask")
			(roundrect_rratio 0.25)
			(net 252 "SYS_SCL")
			(pintype "passive")
		)
		(pad "2" smd roundrect
			(at 0.48 0 90)
			(size 0.59 0.64)
			(layers "B.Cu" "B.Paste" "B.Mask")
			(roundrect_rratio 0.25)
			(net 350 "/Peripherals/GPIOEX_I2C_SCL")
			(pintype "passive")
		)
	)
	(footprint "antmicro-footprints:TSOT23-6"
		(layer "B.Cu")
		(at 93.8 81.78 -90)
		(property "Reference" "U28"
			(at -2.1 -1.05 180)
			(layer "B.SilkS")
			(effects
				(font
					(size 0.7 0.7)
					(thickness 0.15)
				)
				(justify left bottom mirror)
			)
		)
		(property "Value" "AP22615A_TSOT26"
			(at 0 -2.6 90)
			(layer "B.Fab")
			(effects
				(font
					(size 0.7 0.7)
					(thickness 0.15)
				)
				(justify left bottom mirror)
			)
		)
		(property "Footprint" "antmicro-footprints:TSOT23-6"
			(at 0 0 -90)
			(layer "F.Fab")
			(hide yes)
			(effects
				(font
					(size 1.27 1.27)
					(thickness 0.15)
				)
			)
		)
		(property "Datasheet" "https://www.mouser.com/datasheet/2/115/DIOD_S_A0008958405_1-2543193.pdf"
			(at 0 0 -90)
			(layer "F.Fab")
			(hide yes)
			(effects
				(font
					(size 1.27 1.27)
					(thickness 0.15)
				)
			)
		)
		(property "Author" "Antmicro"
			(at 12.02 175.58 0)
			(layer "B.Fab")
			(hide yes)
			(effects
				(font
					(size 1 1)
					(thickness 0.15)
				)
				(justify mirror)
			)
		)
		(property "License" "Apache-2.0"
			(at 12.02 175.58 0)
			(layer "B.Fab")
			(hide yes)
			(effects
				(font
					(size 1 1)
					(thickness 0.15)
				)
				(justify mirror)
			)
		)
		(property "MPN" "AP22615AWU-7"
			(at 12.02 175.58 0)
			(layer "B.Fab")
			(hide yes)
			(effects
				(font
					(size 1 1)
					(thickness 0.15)
				)
				(justify mirror)
			)
		)
		(property "Manufacturer" "Diodes Incorporated"
			(at 12.02 175.58 0)
			(layer "B.Fab")
			(hide yes)
			(effects
				(font
					(size 1 1)
					(thickness 0.15)
				)
				(justify mirror)
			)
		)
		(sheetname "CSI")
		(sheetfile "csi.kicad_sch")
		(attr smd)
		(fp_line
			(start -1 1.5)
			(end 1 1.497)
			(stroke
				(width 0.15)
				(type solid)
			)
			(layer "B.SilkS")
		)
		(fp_line
			(start -1 1.375)
			(end -1 1.5)
			(stroke
				(width 0.15)
				(type solid)
			)
			(layer "B.SilkS")
		)
		(fp_line
			(start 1 1.375)
			(end 1 1.497)
			(stroke
				(width 0.15)
				(type solid)
			)
			(layer "B.SilkS")
		)
		(fp_line
			(start -1 -1.4)
			(end -1 -1.55)
			(stroke
				(width 0.15)
				(type solid)
			)
			(layer "B.SilkS")
		)
		(fp_line
			(start 1 -1.4)
			(end 1 -1.55)
			(stroke
				(width 0.15)
				(type solid)
			)
			(layer "B.SilkS")
		)
		(fp_line
			(start -1 -1.55)
			(end 1 -1.55)
			(stroke
				(width 0.15)
				(type solid)
			)
			(layer "B.SilkS")
		)
		(fp_circle
			(center -1.44 1.5)
			(end -1.39 1.5)
			(stroke
				(width 0.15)
				(type solid)
			)
			(fill solid)
			(layer "B.SilkS")
		)
		(fp_rect
			(start 1.93 1.7)
			(end -1.93 -1.7)
			(stroke
				(width 0.05)
				(type solid)
			)
			(fill none)
			(layer "B.CrtYd")
		)
		(fp_line
			(start -0.876 1.096)
			(end -0.45 1.521)
			(stroke
				(width 0.15)
				(type solid)
			)
			(layer "B.Fab")
		)
		(fp_rect
			(start 0.875 -1.528)
			(end -0.875 1.525)
			(stroke
				(width 0.15)
				(type solid)
			)
			(fill none)
			(layer "B.Fab")
		)
		(fp_text user "${REFERENCE}"
			(at -1.93 -3.8 90)
			(layer "B.Fab")
			(hide yes)
			(effects
				(font
					(size 0.7 0.7)
					(thickness 0.15)
				)
				(justify left bottom mirror)
			)
		)
		(fp_text user "Author: Antmicro"
			(at -1.93 -5 90)
			(layer "B.Fab")
			(hide yes)
			(effects
				(font
					(size 0.7 0.7)
					(thickness 0.15)
				)
				(justify left bottom mirror)
			)
		)
		(fp_text user "License: Apache-2.0"
			(at -1.93 -6.199 90)
			(layer "B.Fab")
			(hide yes)
			(effects
				(font
					(size 0.7 0.7)
					(thickness 0.15)
				)
				(justify left bottom mirror)
			)
		)
		(pad "1" smd rect
			(at -1.301 0.947)
			(size 0.7 1.2)
			(layers "B.Cu" "B.Paste" "B.Mask")
			(net 110 "/CSI/CSIB_3V3")
			(pinfunction "OUT")
			(pintype "power_out")
		)
		(pad "2" smd rect
			(at -1.301 -0.004)
			(size 0.7 1.2)
			(layers "B.Cu" "B.Paste" "B.Mask")
			(net 1 "GND")
			(pinfunction "GND")
			(pintype "power_in")
		)
		(pad "3" smd rect
			(at -1.301 -0.954)
			(size 0.7 1.2)
			(layers "B.Cu" "B.Paste" "B.Mask")
			(net 393 "CSIB_FLG")
			(pinfunction "FLG")
			(pintype "output")
		)
		(pad "4" smd rect
			(at 1.299 -0.954)
			(size 0.7 1.2)
			(layers "B.Cu" "B.Paste" "B.Mask")
			(net 338 "CSIB_PEN")
			(pinfunction "EN")
			(pintype "input")
		)
		(pad "5" smd rect
			(at 1.299 -0.004)
			(size 0.7 1.2)
			(layers "B.Cu" "B.Paste" "B.Mask")
			(net 344 "/CSI/CSIB_3V3_ISET")
			(pinfunction "ISET")
			(pintype "passive")
		)
		(pad "6" smd rect
			(at 1.299 0.947)
			(size 0.7 1.2)
			(layers "B.Cu" "B.Paste" "B.Mask")
			(net 87 "+3V3")
			(pinfunction "IN")
			(pintype "power_in")
		)
	)
	(footprint "antmicro-footprints:R_0402_1005Metric"
		(layer "B.Cu")
		(at 49.98 116.95 180)
		(descr "Resistor SMD 0402")
		(tags "resistor SMD 0402")
		(property "Reference" "R267"
			(at 13.36 -9.229999 0)
			(layer "B.SilkS")
			(effects
				(font
					(size 0.7 0.7)
					(thickness 0.15)
				)
				(justify left bottom mirror)
			)
		)
		(property "Value" "R_1k_0402"
			(at -1.011843 -1.772047 0)
			(layer "B.Fab")
			(effects
				(font
					(size 0.7 0.7)
					(thickness 0.15)
				)
				(justify left bottom mirror)
			)
		)
		(property "Footprint" "antmicro-footprints:R_0402_1005Metric"
			(at 0 0 180)
			(layer "F.Fab")
			(hide yes)
			(effects
				(font
					(size 1.27 1.27)
					(thickness 0.15)
				)
			)
		)
		(property "Datasheet" "https://www.bourns.com/docs/product-datasheets/cr.pdf"
			(at 0 0 180)
			(layer "F.Fab")
			(hide yes)
			(effects
				(font
					(size 1.27 1.27)
					(thickness 0.15)
				)
			)
		)
		(property "Author" "Antmicro"
			(at 99.96 233.9 0)
			(layer "B.Fab")
			(hide yes)
			(effects
				(font
					(size 1 1)
					(thickness 0.15)
				)
				(justify mirror)
			)
		)
		(property "License" "Apache-2.0"
			(at 99.96 233.9 0)
			(layer "B.Fab")
			(hide yes)
			(effects
				(font
					(size 1 1)
					(thickness 0.15)
				)
				(justify mirror)
			)
		)
		(property "MPN" "CR0402-FX-1001GLF"
			(at 99.96 233.9 0)
			(layer "B.Fab")
			(hide yes)
			(effects
				(font
					(size 1 1)
					(thickness 0.15)
				)
				(justify mirror)
			)
		)
		(property "Manufacturer" "Bourns"
			(at 99.96 233.9 0)
			(layer "B.Fab")
			(hide yes)
			(effects
				(font
					(size 1 1)
					(thickness 0.15)
				)
				(justify mirror)
			)
		)
		(property "Tolerance" "1%"
			(at 99.96 233.9 0)
			(layer "B.Fab")
			(hide yes)
			(effects
				(font
					(size 1 1)
					(thickness 0.15)
				)
				(justify mirror)
			)
		)
		(property "Val" "1k"
			(at 99.96 233.9 0)
			(layer "B.Fab")
			(hide yes)
			(effects
				(font
					(size 1 1)
					(thickness 0.15)
				)
				(justify mirror)
			)
		)
		(sheetname "USB Debug, DP")
		(sheetfile "usb.kicad_sch")
		(attr smd)
		(fp_rect
			(start -0.925 0.47)
			(end 0.925 -0.47)
			(stroke
				(width 0.05)
				(type default)
			)
			(fill none)
			(layer "B.CrtYd")
		)
		(fp_rect
			(start -0.5 0.25)
			(end 0.5 -0.25)
			(stroke
				(width 0.15)
				(type solid)
			)
			(fill none)
			(layer "B.Fab")
		)
		(fp_text user "License: Apache-2.0"
			(at -0.95 -5.169 0)
			(layer "B.Fab")
			(hide yes)
			(effects
				(font
					(size 0.7 0.7)
					(thickness 0.15)
				)
				(justify left bottom mirror)
			)
		)
		(fp_text user "${REFERENCE}"
			(at -0.95 -3.168 0)
			(layer "B.Fab")
			(hide yes)
			(effects
				(font
					(size 0.7 0.7)
					(thickness 0.15)
				)
				(justify left bottom mirror)
			)
		)
		(fp_text user "Author: Antmicro"
			(at -0.95 -4.169 0)
			(layer "B.Fab")
			(hide yes)
			(effects
				(font
					(size 0.7 0.7)
					(thickness 0.15)
				)
				(justify left bottom mirror)
			)
		)
		(pad "1" smd roundrect
			(at -0.48 0 180)
			(size 0.59 0.64)
			(layers "B.Cu" "B.Paste" "B.Mask")
			(roundrect_rratio 0.25)
			(net 780 "/USB Debug, DP/FTDI_CBUS0{slash}SDA")
			(pintype "passive")
		)
		(pad "2" smd roundrect
			(at 0.48 0 180)
			(size 0.59 0.64)
			(layers "B.Cu" "B.Paste" "B.Mask")
			(roundrect_rratio 0.25)
			(net 185 "/USB Debug, DP/FTDI_3V3")
			(pintype "passive")
		)
	)
)
